FILE_TYPE = CONNECTIVITY;
{Allegro Design Entry HDL 17.4-2019 S026 (4007227) 1/17/2022}
"PAGE_NUMBER" = 360;
0"NC";
1"GND\g";
2"P3V3_AUX\g";
3"P3V3_AUX\g";
4"P3V3_AUX\g";
5"GND\g";
6"GND\g";
7"GND\g";
8"GND\g";
9"GND\g";
10"M2_0_P3V3_ADC_ALERT";
11"VSENSE_P12V_INA230_4_INN";
12"P3V3\g";
13"OCP_V3_2_P3V3_P12V_ADC_R_ALERT";
14"OCP_V3_2_P3V3_ADC_ALERT_R";
15"NC_INA230_3_NC0";
16"NC_INA230_3_NC1";
17"P12V_SCM\g";
18"P12V_SCM_R\g";
19"SMB_INA230_5_3V3AUX_SDA_R";
20"P3V3_AUX\g";
21"P3V3_AUX\g";
22"P3V3_AUX\g";
23"P3V3_AUX\g";
24"GND\g";
25"GND\g";
26"P3V3_AUX\g";
27"GND\g";
28"GND\g";
29"P3V3_M2_0\g";
30"P12V_SCM_R\g";
31"P3V3_OCP_V3_2\g";
32"P3V3_OCP_V3_2_R\g";
33"GND\g";
34"GND\g";
35"INA230_3_A0";
36"VSENSE_P12V_INA230_3_INP";
37"NC_INA230_4_NC0";
38"NC_INA230_4_NC2";
39"NC_INA230_5_NC2";
40"INA230_5_A1";
41"NC_INA230_4_NC5";
42"SMB_INA230_4_3V3AUX_SDA_R1";
43"NC_INA230_5_NC0";
44"VSENSE_P12V_INA230_5_INN";
45"VSENSE_P12V_INA230_5_INP";
46"INA230_5_A0";
47"NC_INA230_4_NC1";
48"P12V_SCM_ADC_ALERT";
49"NC_INA230_3_NC3";
50"NC_INA230_4_NC3";
51"NC_INA230_5_NC1";
52"NC_INA230_4_NC4";
53"NC_INA230_3_NC5";
54"NC_INA230_3_NC2";
55"NC_INA230_3_NC4";
56"SMB_INA230_3_3V3AUX_SCL_R";
57"SMB_INA230_4_3V3AUX_SCL_R";
58"SMB_INA230_4_3V3AUX_SDA_R";
59"SMB_INA230_3_3V3AUX_SDA_R1";
60"SMB_INA230_5_3V3AUX_SDA_R1";
61"SMB_INA230_5_3V3AUX_SCL_R1";
62"SMB_INA230_5_3V3AUX_SCL_R";
63"SMB_INA230_3_3V3AUX_SCL_R1";
64"VSENSE_P12V_INA230_3_INN";
65"INA230_3_A1";
66"SMB_INA230_4_3V3AUX_SCL_R1";
67"INA230_4_A0";
68"SMB_INA230_3_3V3AUX_SDA_R";
69"P3V3_OCP_V3_2_R\g";
70"INA230_4_A1";
71"VSENSE_P12V_INA230_4_INP";
72"P3V3\g";
73"NC_INA230_5_NC3";
74"NC_INA230_5_NC4";
75"NC_INA230_5_NC5";
76"P12V_SCM_ADC_ALERT_R";
77"M2_0_P3V3_ADC_ALERT_R";
%"Q_RES"
"2","(525,350)","0","pure_quanta","I100";
;
LOCATION"R3620"
$SEC"1"
CDS_SEC"1"
TOLERANCE"5%"
PACK_TYPE"0402LF"
VALUE"0"
WATTAGE"1/16W"
MATERIAL"CHIP"
CDS_LIB"pure_quanta"
PART_NUMBER"CS00002JB13";
"A"
$PN"1"35;
"B"
$PN"2"63;
%"Q_RES"
"1","(-525,600)","0","pure_quanta","I103";
;
LOCATION"R3608"
$SEC"1"
CDS_SEC"1"
PACK_TYPE"0402LF"
MATERIAL"CHIP"
WATTAGE"1/16W"
VALUE"4.7K"
TOLERANCE"1%"
CDS_LIB"pure_quanta"
PART_NUMBER"CS24702FB06";
"B"
$PN"2"65;
"A"
$PN"1"34;
%"Q_RES"
"1","(-525,525)","0","pure_quanta","I104";
;
LOCATION"R3609"
$SEC"1"
CDS_SEC"1"
PACK_TYPE"0402LF"
WATTAGE"1/16W"
VALUE"4.7K"
MATERIAL"EMPTY"
TOLERANCE"1%"
CDS_LIB"pure_quanta"
PART_NUMBER"CS24702FB06";
"B"
$PN"2"35;
"A"
$PN"1"34;
%"UNIVERSAL_GND"
"1","(-950,400)","0","pure_quanta_power","I105";
;
CDS_LIB"pure_quanta_power"
HDL_POWER"GND";
"A"34;
%"UNIVERSAL_GND"
"1","(2350,-525)","0","pure_quanta_power","I107";
;
CDS_LIB"pure_quanta_power"
HDL_POWER"GND";
"A"33;
%"Q_CAP"
"1","(500,-625)","0","pure_quanta","I108";
;
LOCATION"C2020"
$SEC"1"
CDS_SEC"1"
PACK_TYPE"0402"
MATERIAL"X7R"
VOLTAGE"25V"
VALUE"0.1UF"
TOLERANCE"10%"
CDS_LIB"pure_quanta"
PART_NUMBER"CH4104K1B00";
"B"
$PN"2"64;
"A"
$PN"1"36;
%"Q_RES"
"1","(150,-475)","0","pure_quanta","I109";
;
LOCATION"R3570"
$SEC"1"
CDS_SEC"1"
MATERIAL"CHIP"
TOLERANCE"1%"
VALUE"10"
WATTAGE"1/16W"
PACK_TYPE"0402LF"
CDS_LIB"pure_quanta"
PART_NUMBER"CS01002FB07";
"B"
$PN"2"36;
"A"
$PN"1"32;
%"Q_RES"
"1","(150,-750)","0","pure_quanta","I110";
;
LOCATION"R3571"
$SEC"1"
CDS_SEC"1"
PACK_TYPE"0402LF"
WATTAGE"1/16W"
TOLERANCE"1%"
VALUE"10"
MATERIAL"CHIP"
CDS_LIB"pure_quanta"
PART_NUMBER"CS01002FB07";
"B"
$PN"2"64;
"A"
$PN"1"31;
%"UNIVERSAL_POWER"
"1","(-1250,-125)","0","pure_quanta_power","I112";
;
HDL_POWER"P3V3_OCP_V3_2_R"
CDS_LIB"pure_quanta_power";
"A"32;
%"UNIVERSAL_POWER"
"1","(-1400,625)","0","pure_quanta_power","I113";
;
HDL_POWER"P3V3_OCP_V3_2_R"
CDS_LIB"pure_quanta_power";
"A"69;
%"Q_CAP"
"1","(-1650,300)","0","pure_quanta","I114";
;
LOCATION"C2017"
$SEC"1"
CDS_SEC"1"
VALUE"0.1UF"
VOLTAGE"25V"
TOLERANCE"10%"
PACK_TYPE"0402"
MATERIAL"X7R"
CDS_LIB"pure_quanta"
PART_NUMBER"CH4104K1B00";
"B"
$PN"2"1;
"A"
$PN"1"69;
%"UNIVERSAL_GND"
"1","(-1650,25)","0","pure_quanta_power","I115";
;
CDS_LIB"pure_quanta_power"
HDL_POWER"GND";
"A"1;
%"Q_RES"
"1","(-1750,-275)","0","pure_quanta","I116";
;
LOCATION"R3633"
$SEC"1"
CDS_SEC"1"
PACK_TYPE"2512LF"
MATERIAL"CHIP"
VALUE"0.002"
TOLERANCE"1%"
WATTAGE"2W"
CDS_LIB"pure_quanta"
PART_NUMBER"CS+002AFR06";
"B"
$PN"2"32;
"A"
$PN"1"31;
%"UNIVERSAL_POWER"
"1","(-2325,-125)","0","pure_quanta_power","I117";
;
HDL_POWER"P3V3_OCP_V3_2"
CDS_LIB"pure_quanta_power";
"A"31;
%"UNIVERSAL_POWER"
"1","(-2625,-4375)","0","pure_quanta_power","I118";
;
HDL_POWER"P12V_SCM"
CDS_LIB"pure_quanta_power";
"A"17;
%"UNIVERSAL_POWER"
"1","(-1550,-4375)","0","pure_quanta_power","I119";
;
HDL_POWER"P12V_SCM_R"
CDS_LIB"pure_quanta_power";
"A"30;
%"UNIVERSAL_POWER"
"1","(-1700,-3625)","0","pure_quanta_power","I120";
;
HDL_POWER"P12V_SCM_R"
CDS_LIB"pure_quanta_power";
"A"18;
%"UNIVERSAL_POWER"
"1","(2675,-3225)","0","pure_quanta_power","I121";
;
HDL_POWER"P3V3_AUX"
CDS_LIB"pure_quanta_power";
"A"2;
%"Q_RES"
"2","(2675,-3425)","0","pure_quanta","I122";
;
LOCATION"R4091"
$SEC"1"
CDS_SEC"1"
MATERIAL"CHIP"
WATTAGE"1/16W"
TOLERANCE"1%"
PACK_TYPE"0402LF"
VALUE"1K"
CDS_LIB"pure_quanta"
PART_NUMBER"CS21002FB06";
"A"
$PN"1"2;
"B"
$PN"2"76;
%"UNIVERSAL_POWER"
"1","(2600,-1075)","0","pure_quanta_power","I123";
;
HDL_POWER"P3V3_AUX"
CDS_LIB"pure_quanta_power";
"A"3;
%"Q_RES"
"2","(2600,-1275)","0","pure_quanta","I124";
;
LOCATION"R4090"
$SEC"1"
CDS_SEC"1"
MATERIAL"CHIP"
PACK_TYPE"0402LF"
TOLERANCE"1%"
WATTAGE"1/16W"
VALUE"1K"
CDS_LIB"pure_quanta"
PART_NUMBER"CS21002FB06";
"A"
$PN"1"3;
"B"
$PN"2"77;
%"UNIVERSAL_POWER"
"1","(3175,1025)","0","pure_quanta_power","I125";
;
HDL_POWER"P3V3_AUX"
CDS_LIB"pure_quanta_power";
"A"4;
%"Q_RES"
"2","(3175,825)","0","pure_quanta","I126";
;
LOCATION"R4092"
$SEC"1"
CDS_SEC"1"
MATERIAL"CHIP"
WATTAGE"1/16W"
PACK_TYPE"0402LF"
TOLERANCE"1%"
VALUE"1K"
CDS_LIB"pure_quanta"
PART_NUMBER"CS21002FB06";
"A"
$PN"1"4;
"B"
$PN"2"14;
%"Q_RES"
"1","(100,75)","0","pure_quanta","I127";
;
LOCATION"R3569"
$SEC"1"
CDS_SEC"1"
VALUE"0"
TOLERANCE"5%"
MATERIAL"CHIP"
CDS_LIB"pure_quanta"
PACK_TYPE"0402LF"
WATTAGE"1/16W"
PART_NUMBER"CS00002JB13";
"B"
$PN"2"59;
"A"
$PN"1"68;
%"Q_RES"
"1","(100,125)","0","pure_quanta","I128";
;
LOCATION"R3568"
$SEC"1"
CDS_SEC"1"
TOLERANCE"5%"
PACK_TYPE"0402LF"
VALUE"0"
WATTAGE"1/16W"
MATERIAL"CHIP"
CDS_LIB"pure_quanta"
PART_NUMBER"CS00002JB13";
"B"
$PN"2"63;
"A"
$PN"1"56;
%"Q_RES"
"1","(-300,-2025)","0","pure_quanta","I129";
;
LOCATION"R3573"
$SEC"1"
CDS_SEC"1"
TOLERANCE"5%"
MATERIAL"CHIP"
VALUE"0"
WATTAGE"1/16W"
PACK_TYPE"0402LF"
CDS_LIB"pure_quanta"
PART_NUMBER"CS00002JB13";
"B"
$PN"2"42;
"A"
$PN"1"58;
%"Q_RES"
"1","(-300,-1975)","0","pure_quanta","I130";
;
LOCATION"R3572"
$SEC"1"
CDS_SEC"1"
VALUE"0"
TOLERANCE"5%"
PACK_TYPE"0402LF"
MATERIAL"CHIP"
WATTAGE"1/16W"
CDS_LIB"pure_quanta"
PART_NUMBER"CS00002JB13";
"B"
$PN"2"66;
"A"
$PN"1"57;
%"Q_RES"
"1","(-175,-4125)","0","pure_quanta","I131";
;
LOCATION"R3576"
$SEC"1"
CDS_SEC"1"
WATTAGE"1/16W"
MATERIAL"CHIP"
TOLERANCE"5%"
VALUE"0"
PACK_TYPE"0402LF"
CDS_LIB"pure_quanta"
PART_NUMBER"CS00002JB13";
"B"
$PN"2"61;
"A"
$PN"1"62;
%"Q_RES"
"1","(-175,-4175)","0","pure_quanta","I132";
;
LOCATION"R3577"
$SEC"1"
CDS_SEC"1"
VALUE"0"
TOLERANCE"5%"
MATERIAL"CHIP"
PACK_TYPE"0402LF"
WATTAGE"1/16W"
CDS_LIB"pure_quanta"
PART_NUMBER"CS00002JB13";
"B"
$PN"2"60;
"A"
$PN"1"19;
%"UNIVERSAL_POWER"
"1","(-2750,-2225)","0","pure_quanta_power","I24";
;
HDL_POWER"P3V3_M2_0"
CDS_LIB"pure_quanta_power";
"A"29;
%"Q_CAP"
"1","(-2075,-1800)","0","pure_quanta","I26";
;
LOCATION"C2018"
$SEC"1"
CDS_SEC"1"
VALUE"0.1UF"
VOLTAGE"25V"
TOLERANCE"10%"
MATERIAL"X7R"
PACK_TYPE"0402"
CDS_LIB"pure_quanta"
PART_NUMBER"CH4104K1B00";
"B"
$PN"2"5;
"A"
$PN"1"12;
%"UNIVERSAL_GND"
"1","(-2075,-2075)","0","pure_quanta_power","I27";
;
CDS_LIB"pure_quanta_power"
HDL_POWER"GND";
"A"5;
%"UNIVERSAL_GND"
"1","(-1475,-1875)","0","pure_quanta_power","I31";
;
CDS_LIB"pure_quanta_power"
HDL_POWER"GND";
"A"28;
%"UNIVERSAL_POWER"
"1","(-1825,-1475)","0","pure_quanta_power","I32";
;
HDL_POWER"P3V3"
CDS_LIB"pure_quanta_power";
"A"12;
%"Q_RES"
"1","(-275,-2850)","0","pure_quanta","I33";
;
LOCATION"R3575"
$SEC"1"
CDS_SEC"1"
PACK_TYPE"0402LF"
WATTAGE"1/16W"
MATERIAL"CHIP"
TOLERANCE"1%"
VALUE"10"
CDS_LIB"pure_quanta"
PART_NUMBER"CS01002FB07";
"B"
$PN"2"11;
"A"
$PN"1"29;
%"Q_RES"
"1","(-275,-2575)","0","pure_quanta","I35";
;
LOCATION"R3574"
$SEC"1"
CDS_SEC"1"
PACK_TYPE"0402LF"
WATTAGE"1/16W"
MATERIAL"CHIP"
VALUE"10"
TOLERANCE"1%"
CDS_LIB"pure_quanta"
PART_NUMBER"CS01002FB07";
"B"
$PN"2"71;
"A"
$PN"1"72;
%"Q_RES"
"1","(-1050,-1750)","0","pure_quanta","I36";
;
LOCATION"R3611"
$SEC"1"
CDS_SEC"1"
PACK_TYPE"0402LF"
TOLERANCE"1%"
WATTAGE"1/16W"
MATERIAL"CHIP"
VALUE"4.7K"
CDS_LIB"pure_quanta"
PART_NUMBER"CS24702FB06";
"B"
$PN"2"67;
"A"
$PN"1"28;
%"UNIVERSAL_GND"
"1","(600,-1650)","0","pure_quanta_power","I39";
;
CDS_LIB"pure_quanta_power"
HDL_POWER"GND";
"A"6;
%"UNIVERSAL_GND"
"1","(1925,-2625)","0","pure_quanta_power","I40";
;
CDS_LIB"pure_quanta_power"
HDL_POWER"GND";
"A"27;
%"Q_RES"
"1","(2800,-1725)","0","pure_quanta","I41";
;
LOCATION"R3560"
$SEC"1"
CDS_SEC"1"
MATERIAL"CHIP"
PACK_TYPE"0402LF"
VALUE"0"
CDS_LIB"pure_quanta"
TOLERANCE"5%"
WATTAGE"1/16W"
PART_NUMBER"CS00002JB13";
"B"
$PN"2"10;
"A"
$PN"1"77;
%"Q_CAP"
"1","(600,-1375)","0","pure_quanta","I42";
;
LOCATION"C2013"
$SEC"1"
CDS_SEC"1"
MATERIAL"X7R"
VALUE"0.1UF"
VOLTAGE"25V"
TOLERANCE"10%"
PACK_TYPE"0402"
CDS_LIB"pure_quanta"
PART_NUMBER"CH4104K1B00";
"B"
$PN"2"6;
"A"
$PN"1"26;
%"UNIVERSAL_POWER"
"1","(850,-975)","0","pure_quanta_power","I43";
;
HDL_POWER"P3V3_AUX"
CDS_LIB"pure_quanta_power";
"A"26;
%"Q_RES"
"1","(-1050,-1675)","0","pure_quanta","I45";
;
LOCATION"R3610"
$SEC"1"
CDS_SEC"1"
PACK_TYPE"0402LF"
VALUE"4.7K"
TOLERANCE"1%"
WATTAGE"1/16W"
MATERIAL"EMPTY"
CDS_LIB"pure_quanta"
PART_NUMBER"CS24702FB06";
"B"
$PN"2"70;
"A"
$PN"1"28;
%"ISL28022FRZT"
"1","(1350,-1975)","0","pure_quanta","I46";
;
LOCATION"U264"
SEC"1"
MATERIAL"IC"
PART_TYPE"SMLF"
VALUE"ISL28022FRZ-T"
CDS_LIB"pure_quanta"
NEEDS_NO_SIZE"TRUE"
CDS_LMAN_SYM_OUTLINE"-300,300,300,-300"
SEC_TYPE""
PART_NUMBER"AL028022003";
"TH_GND"
$PN"TH"27;
"GND"
$PN"10"27;
"NC5"
$PN"16"41;
"NC4"
$PN"15"52;
"NC3"
$PN"14"50;
"NC2"
$PN"8"38;
"NC1"
$PN"7"47;
"NC0"
$PN"6"37;
"EXT_CLK||INT"
$PN"3"77;
"VINM"
$PN"12"11;
"VINP"
$PN"13"71;
"VBUS"
$PN"11"12;
"SDA||SMBDAT"
$PN"4"42;
"SCL|||SMBCLK"
$PN"5"66;
"A0"
$PN"2"67;
"A1"
$PN"1"70;
"VCC"
$PN"9"26;
%"Q_CAP"
"1","(-1950,-3950)","0","pure_quanta","I49";
;
LOCATION"C2019"
$SEC"1"
CDS_SEC"1"
PACK_TYPE"0402"
VALUE"0.1UF"
MATERIAL"X7R"
VOLTAGE"25V"
TOLERANCE"10%"
CDS_LIB"pure_quanta"
PART_NUMBER"CH4104K1B00";
"B"
$PN"2"7;
"A"
$PN"1"18;
%"UNIVERSAL_GND"
"1","(-1950,-4225)","0","pure_quanta_power","I50";
;
CDS_LIB"pure_quanta_power"
HDL_POWER"GND";
"A"7;
%"UNIVERSAL_GND"
"1","(-1400,-4050)","0","pure_quanta_power","I54";
;
CDS_LIB"pure_quanta_power"
HDL_POWER"GND";
"A"25;
%"Q_RES"
"1","(-150,-5000)","0","pure_quanta","I56";
;
LOCATION"R3579"
$SEC"1"
CDS_SEC"1"
WATTAGE"1/16W"
TOLERANCE"1%"
VALUE"10"
PACK_TYPE"0402LF"
MATERIAL"CHIP"
CDS_LIB"pure_quanta"
PART_NUMBER"CS01002FB07";
"B"
$PN"2"44;
"A"
$PN"1"17;
%"Q_RES"
"1","(-150,-4725)","0","pure_quanta","I58";
;
LOCATION"R3578"
$SEC"1"
CDS_SEC"1"
MATERIAL"CHIP"
VALUE"10"
TOLERANCE"1%"
PACK_TYPE"0402LF"
WATTAGE"1/16W"
CDS_LIB"pure_quanta"
PART_NUMBER"CS01002FB07";
"B"
$PN"2"45;
"A"
$PN"1"30;
%"Q_RES"
"1","(-975,-3925)","0","pure_quanta","I59";
;
LOCATION"R3613"
$SEC"1"
CDS_SEC"1"
WATTAGE"1/16W"
MATERIAL"EMPTY"
PACK_TYPE"0402LF"
TOLERANCE"1%"
VALUE"4.7K"
CDS_LIB"pure_quanta"
PART_NUMBER"CS24702FB06";
"B"
$PN"2"46;
"A"
$PN"1"25;
%"UNIVERSAL_GND"
"1","(725,-3800)","0","pure_quanta_power","I62";
;
CDS_LIB"pure_quanta_power"
HDL_POWER"GND";
"A"8;
%"UNIVERSAL_GND"
"1","(2050,-4775)","0","pure_quanta_power","I63";
;
CDS_LIB"pure_quanta_power"
HDL_POWER"GND";
"A"24;
%"Q_RES"
"1","(2925,-3875)","0","pure_quanta","I64";
;
LOCATION"R3561"
$SEC"1"
CDS_SEC"1"
VALUE"0"
MATERIAL"CHIP"
PACK_TYPE"0402LF"
WATTAGE"1/16W"
TOLERANCE"5%"
CDS_LIB"pure_quanta"
PART_NUMBER"CS00002JB13";
"B"
$PN"2"48;
"A"
$PN"1"76;
%"Q_CAP"
"1","(725,-3525)","0","pure_quanta","I65";
;
LOCATION"C2014"
$SEC"1"
CDS_SEC"1"
TOLERANCE"10%"
VOLTAGE"25V"
VALUE"0.1UF"
MATERIAL"X7R"
PACK_TYPE"0402"
CDS_LIB"pure_quanta"
PART_NUMBER"CH4104K1B00";
"B"
$PN"2"8;
"A"
$PN"1"23;
%"UNIVERSAL_POWER"
"1","(975,-3125)","0","pure_quanta_power","I66";
;
HDL_POWER"P3V3_AUX"
CDS_LIB"pure_quanta_power";
"A"23;
%"Q_RES"
"1","(-975,-3850)","0","pure_quanta","I68";
;
LOCATION"R3612"
$SEC"1"
CDS_SEC"1"
WATTAGE"1/16W"
MATERIAL"EMPTY"
TOLERANCE"1%"
VALUE"4.7K"
PACK_TYPE"0402LF"
CDS_LIB"pure_quanta"
PART_NUMBER"CS24702FB06";
"B"
$PN"2"40;
"A"
$PN"1"25;
%"ISL28022FRZT"
"1","(1475,-4125)","0","pure_quanta","I69";
;
LOCATION"U265"
SEC"1"
PART_TYPE"SMLF"
MATERIAL"IC"
VALUE"ISL28022FRZ-T"
SEC_TYPE""
CDS_LMAN_SYM_OUTLINE"-300,300,300,-300"
NEEDS_NO_SIZE"TRUE"
CDS_LIB"pure_quanta"
PART_NUMBER"AL028022003";
"TH_GND"
$PN"TH"24;
"GND"
$PN"10"24;
"NC5"
$PN"16"75;
"NC4"
$PN"15"74;
"NC3"
$PN"14"73;
"NC2"
$PN"8"39;
"NC1"
$PN"7"51;
"NC0"
$PN"6"43;
"EXT_CLK||INT"
$PN"3"76;
"VINM"
$PN"12"44;
"VINP"
$PN"13"45;
"VBUS"
$PN"11"18;
"SDA||SMBDAT"
$PN"4"60;
"SCL|||SMBCLK"
$PN"5"61;
"A0"
$PN"2"46;
"A1"
$PN"1"40;
"VCC"
$PN"9"23;
%"Q_CAP"
"1","(75,-2725)","0","pure_quanta","I71";
;
LOCATION"C2021"
$SEC"1"
CDS_SEC"1"
TOLERANCE"10%"
MATERIAL"X7R"
PACK_TYPE"0402"
VALUE"0.1UF"
VOLTAGE"25V"
CDS_LIB"pure_quanta"
PART_NUMBER"CH4104K1B00";
"B"
$PN"2"11;
"A"
$PN"1"71;
%"Q_CAP"
"1","(200,-4875)","0","pure_quanta","I72";
;
LOCATION"C2022"
$SEC"1"
CDS_SEC"1"
PACK_TYPE"0402"
MATERIAL"X7R"
TOLERANCE"10%"
VOLTAGE"25V"
VALUE"0.1UF"
CDS_LIB"pure_quanta"
PART_NUMBER"CH4104K1B00";
"B"
$PN"2"44;
"A"
$PN"1"45;
%"UNIVERSAL_POWER"
"1","(-1675,-2225)","0","pure_quanta_power","I76";
;
HDL_POWER"P3V3"
CDS_LIB"pure_quanta_power";
"A"72;
%"UNIVERSAL_POWER"
"1","(75,-1025)","0","pure_quanta_power","I85";
;
HDL_POWER"P3V3_AUX"
CDS_LIB"pure_quanta_power";
"A"22;
%"Q_RES"
"2","(75,-1325)","0","pure_quanta","I86";
;
LOCATION"R3623"
$SEC"1"
CDS_SEC"1"
VALUE"4.7K"
WATTAGE"1/16W"
TOLERANCE"1%"
MATERIAL"CHIP"
PACK_TYPE"0402LF"
CDS_LIB"pure_quanta"
PART_NUMBER"CS24702FB06";
"A"
$PN"1"22;
"B"
$PN"2"70;
%"Q_RES"
"2","(-225,-1325)","0","pure_quanta","I87";
;
LOCATION"R3621"
$SEC"1"
CDS_SEC"1"
MATERIAL"EMPTY"
PACK_TYPE"0402LF"
VALUE"4.7K"
TOLERANCE"1%"
WATTAGE"1/16W"
CDS_LIB"pure_quanta"
PART_NUMBER"CS24702FB06";
"A"
$PN"1"22;
"B"
$PN"2"67;
%"UNIVERSAL_POWER"
"1","(125,-3225)","0","pure_quanta_power","I88";
;
HDL_POWER"P3V3_AUX"
CDS_LIB"pure_quanta_power";
"A"21;
%"Q_RES"
"2","(125,-3525)","0","pure_quanta","I89";
;
LOCATION"R3624"
$SEC"1"
CDS_SEC"1"
PACK_TYPE"0402LF"
MATERIAL"CHIP"
VALUE"4.7K"
TOLERANCE"1%"
WATTAGE"1/16W"
CDS_LIB"pure_quanta"
PART_NUMBER"CS24702FB06";
"A"
$PN"1"21;
"B"
$PN"2"40;
%"Q_RES"
"2","(-175,-3525)","0","pure_quanta","I90";
;
LOCATION"R3622"
$SEC"1"
CDS_SEC"1"
WATTAGE"1/16W"
TOLERANCE"1%"
MATERIAL"CHIP"
PACK_TYPE"0402LF"
VALUE"4.7K"
CDS_LIB"pure_quanta"
PART_NUMBER"CS24702FB06";
"A"
$PN"1"21;
"B"
$PN"2"46;
%"Q_RES"
"1","(-2150,-2375)","0","pure_quanta","I92";
;
LOCATION"R3634"
$SEC"1"
CDS_SEC"1"
PACK_TYPE"2512LF"
TOLERANCE"1%"
VALUE"0.002"
WATTAGE"2W"
MATERIAL"CHIP"
CDS_LIB"pure_quanta"
PART_NUMBER"CS+002AFR06";
"B"
$PN"2"72;
"A"
$PN"1"29;
%"Q_RES"
"1","(-2050,-4525)","0","pure_quanta","I93";
;
LOCATION"R3635"
$SEC"1"
CDS_SEC"1"
TOLERANCE"1%"
VALUE"0.002"
WATTAGE"2W"
PACK_TYPE"2512LF"
MATERIAL"CHIP"
CDS_LIB"pure_quanta"
PART_NUMBER"CS+002AFR06";
"B"
$PN"2"30;
"A"
$PN"1"17;
%"ISL28022FRZT"
"1","(1775,125)","0","pure_quanta","I94";
;
LOCATION"U263"
SEC"1"
VALUE"ISL28022FRZ-T"
PART_TYPE"SMLF"
MATERIAL"IC"
SEC_TYPE""
CDS_LMAN_SYM_OUTLINE"-300,300,300,-300"
NEEDS_NO_SIZE"TRUE"
CDS_LIB"pure_quanta"
PART_NUMBER"AL028022003";
"TH_GND"
$PN"TH"33;
"GND"
$PN"10"33;
"NC5"
$PN"16"53;
"NC4"
$PN"15"55;
"NC3"
$PN"14"49;
"NC2"
$PN"8"54;
"NC1"
$PN"7"16;
"NC0"
$PN"6"15;
"EXT_CLK||INT"
$PN"3"14;
"VINM"
$PN"12"64;
"VINP"
$PN"13"36;
"VBUS"
$PN"11"69;
"SDA||SMBDAT"
$PN"4"59;
"SCL|||SMBCLK"
$PN"5"63;
"A0"
$PN"2"35;
"A1"
$PN"1"65;
"VCC"
$PN"9"20;
%"Q_RES"
"1","(3375,375)","0","pure_quanta","I96";
;
LOCATION"R3559"
$SEC"1"
CDS_SEC"1"
MATERIAL"CHIP"
VALUE"0"
PACK_TYPE"0402LF"
CDS_LIB"pure_quanta"
TOLERANCE"5%"
WATTAGE"1/16W"
PART_NUMBER"CS00002JB13";
"B"
$PN"2"13;
"A"
$PN"1"14;
%"UNIVERSAL_POWER"
"1","(1275,1125)","0","pure_quanta_power","I97";
;
HDL_POWER"P3V3_AUX"
CDS_LIB"pure_quanta_power";
"A"20;
%"Q_CAP"
"1","(1025,725)","0","pure_quanta","I98";
;
LOCATION"C2012"
$SEC"1"
CDS_SEC"1"
PACK_TYPE"0402"
VALUE"0.1UF"
VOLTAGE"25V"
TOLERANCE"10%"
MATERIAL"X7R"
CDS_LIB"pure_quanta"
PART_NUMBER"CH4104K1B00";
"B"
$PN"2"9;
"A"
$PN"1"20;
%"UNIVERSAL_GND"
"1","(1025,450)","0","pure_quanta_power","I99";
;
CDS_LIB"pure_quanta_power"
HDL_POWER"GND";
"A"9;
END.
